# T6G (Grand Teton) — schematic netlist excerpt (pin names and nets, part order shuffled) for the footprints in the layout excerpt that follows; sources: Cadence DE-HDL packaged netlist, KiCad conversion of 04192023_DAF0TMB3IC0_F0TG_MB_C_brd_V02_OCP.brd

C678  Q_CAP_DIFFBUS  DIFF BUS_0.22UF 6.3V 20% X6S  pkg C0201  page 67 : \1\ = P5E_CPU1_G1_TX_C_DN<15> ; \2\ = P5E_CPU1_G1_TX_DN<15>
PR105  Q_RES  8.87K 1% EMPTY  pkg 0402LF  page 206 : A = PVDDIO_P0_LSET4 ; B = GND
PR223  Q_RES  1.5 1% EMPTY  pkg 0402LF  page 205 : A = SW_PVDDIO_P0_SW2_RC ; B = GND

(kicad_pcb
	(version 20260206)
	(generator "pcbnew")
	(generator_version "10.0")
	(general
		(thickness 1.6)
		(legacy_teardrops no)
	)
	(paper "A4")
	(title_block
		(title "04192023_DAF0TMB3IC0_F0TG_MB_C_brd_V02_OCP.brd")
		(comment 1 "Grand Teton / footprints 4043-4045 of 8354")
	)
	(layers
		(0 "F.Cu" signal "TOP")
		(4 "In1.Cu" signal "GND")
		(6 "In2.Cu" signal "IN1")
		(8 "In3.Cu" signal "GND1")
		(10 "In4.Cu" signal "IN2")
		(12 "In5.Cu" signal "GND2")
		(14 "In6.Cu" signal "IN3")
		(16 "In7.Cu" signal "GND3")
		(18 "In8.Cu" signal "VCC")
		(20 "In9.Cu" signal "VCC1")
		(22 "In10.Cu" signal "GND4")
		(24 "In11.Cu" signal "IN4")
		(26 "In12.Cu" signal "GND5")
		(28 "In13.Cu" signal "IN5")
		(30 "In14.Cu" signal "GND6")
		(32 "In15.Cu" signal "IN6")
		(34 "In16.Cu" signal "GND7")
		(2 "B.Cu" signal "BOTTOM")
		(9 "F.Adhes" user "F.Adhesive")
		(11 "B.Adhes" user "B.Adhesive")
		(13 "F.Paste" user "Package Geometry/Pastemask Top")
		(15 "B.Paste" user "Package Geometry/Pastemask Bottom")
		(5 "F.SilkS" user "Ref Des/Silkscreen Top")
		(7 "B.SilkS" user "Ref Des/Silkscreen Bottom")
		(1 "F.Mask" user "Board Geometry/Soldermask Top")
		(3 "B.Mask" user "Board Geometry/Soldermask Bottom")
		(17 "Dwgs.User" user "User.Drawings")
		(19 "Cmts.User" user "User.Comments")
		(21 "Eco1.User" user "User.Eco1")
		(23 "Eco2.User" user "User.Eco2")
		(25 "Edge.Cuts" user "Board Geometry/Outline")
		(27 "Margin" user)
		(31 "F.CrtYd" user "Package Geometry/Place Bound Top")
		(29 "B.CrtYd" user "Package Geometry/Place Bound Bottom")
		(35 "F.Fab" user "Ref Des/Assembly Top")
		(33 "B.Fab" user "Ref Des/Assembly Bottom")
	)
	(footprint ""
		(layer "F.Cu")
		(at 15.508478 -16.099536 90)
		(property "Reference" "C678"
			(at 0 0 90)
			(layer "F.SilkS")
			(hide yes)
			(effects
				(font
					(size 1.27 1.27)
				)
			)
		)
		(property "Value" ""
			(at 0 0 90)
			(layer "F.Fab")
			(effects
				(font
					(size 1.27 1.27)
				)
			)
		)
		(duplicate_pad_numbers_are_jumpers no)
		(fp_line
			(start 0.299974 -0.150114)
			(end 0.299974 0.150114)
			(stroke
				(width 0.1)
				(type default)
			)
			(layer "F.Fab")
		)
		(fp_line
			(start -0.299974 -0.150114)
			(end 0.299974 -0.150114)
			(stroke
				(width 0.1)
				(type default)
			)
			(layer "F.Fab")
		)
		(fp_line
			(start 0.299974 0.150114)
			(end -0.299974 0.150114)
			(stroke
				(width 0.1)
				(type default)
			)
			(layer "F.Fab")
		)
		(fp_line
			(start -0.299974 0.150114)
			(end -0.299974 -0.150114)
			(stroke
				(width 0.1)
				(type default)
			)
			(layer "F.Fab")
		)
		(pad "1" smd rect
			(at -0.2667 0 90)
			(size 0.3048 0.381)
			(layers "F.Cu" "F.Mask" "F.Paste")
			(net "P5E_CPU1_G1_TX_C_DN<15>")
		)
		(pad "2" smd rect
			(at 0.2667 0 90)
			(size 0.3048 0.381)
			(layers "F.Cu" "F.Mask" "F.Paste")
			(net "P5E_CPU1_G1_TX_DN<15>")
		)
	)
	(footprint ""
		(layer "F.Cu")
		(at 288.331148 -344.982038 90)
		(property "Reference" "PR223"
			(at 0 0 90)
			(layer "F.SilkS")
			(hide yes)
			(effects
				(font
					(size 1.27 1.27)
				)
			)
		)
		(property "Value" ""
			(at 0 0 90)
			(layer "F.Fab")
			(effects
				(font
					(size 1.27 1.27)
				)
			)
		)
		(duplicate_pad_numbers_are_jumpers no)
		(fp_line
			(start 0.7874 -0.4064)
			(end 0.7874 0.4064)
			(stroke
				(width 0.1524)
				(type default)
			)
			(layer "F.SilkS")
		)
		(fp_line
			(start -0.7874 -0.4064)
			(end 0.7874 -0.4064)
			(stroke
				(width 0.1524)
				(type default)
			)
			(layer "F.SilkS")
		)
		(fp_line
			(start 0.7874 0.4064)
			(end -0.7874 0.4064)
			(stroke
				(width 0.1524)
				(type default)
			)
			(layer "F.SilkS")
		)
		(fp_line
			(start -0.7874 0.4064)
			(end -0.7874 -0.4064)
			(stroke
				(width 0.1524)
				(type default)
			)
			(layer "F.SilkS")
		)
		(fp_line
			(start -0.12065 -0.305054)
			(end -0.12065 -0.2794)
			(stroke
				(width 0.1)
				(type default)
			)
			(layer "F.Fab")
		)
		(fp_line
			(start -0.67945 -0.305054)
			(end -0.12065 -0.305054)
			(stroke
				(width 0.1)
				(type default)
			)
			(layer "F.Fab")
		)
		(fp_line
			(start 0.67945 -0.3048)
			(end 0.67945 0.3048)
			(stroke
				(width 0.1)
				(type default)
			)
			(layer "F.Fab")
		)
		(fp_line
			(start 0.12065 -0.3048)
			(end 0.67945 -0.3048)
			(stroke
				(width 0.1)
				(type default)
			)
			(layer "F.Fab")
		)
		(fp_line
			(start 0.12065 -0.2794)
			(end 0.12065 -0.3048)
			(stroke
				(width 0.1)
				(type default)
			)
			(layer "F.Fab")
		)
		(fp_line
			(start -0.12065 -0.2794)
			(end 0.12065 -0.2794)
			(stroke
				(width 0.1)
				(type default)
			)
			(layer "F.Fab")
		)
		(fp_line
			(start 0.120396 0.2794)
			(end -0.12065 0.2794)
			(stroke
				(width 0.1)
				(type default)
			)
			(layer "F.Fab")
		)
		(fp_line
			(start -0.12065 0.2794)
			(end -0.12065 0.3048)
			(stroke
				(width 0.1)
				(type default)
			)
			(layer "F.Fab")
		)
		(fp_line
			(start 0.67945 0.3048)
			(end 0.120396 0.3048)
			(stroke
				(width 0.1)
				(type default)
			)
			(layer "F.Fab")
		)
		(fp_line
			(start 0.120396 0.3048)
			(end 0.120396 0.2794)
			(stroke
				(width 0.1)
				(type default)
			)
			(layer "F.Fab")
		)
		(fp_line
			(start -0.12065 0.3048)
			(end -0.67945 0.3048)
			(stroke
				(width 0.1)
				(type default)
			)
			(layer "F.Fab")
		)
		(fp_line
			(start -0.67945 0.3048)
			(end -0.67945 -0.305054)
			(stroke
				(width 0.1)
				(type default)
			)
			(layer "F.Fab")
		)
		(pad "1" smd circle
			(at -0.40005 0 90)
			(size 0 0)
			(layers "F.Cu" "F.Mask" "F.Paste")
			(net "SW_PVDDIO_P0_SW2_RC")
		)
		(pad "2" smd circle
			(at 0.40005 0 90)
			(size 0 0)
			(layers "F.Cu" "F.Mask" "F.Paste")
			(net "GND")
		)
	)
	(footprint ""
		(layer "F.Cu")
		(at 274.117562 -351.927922)
		(property "Reference" "PR105"
			(at 0 0 0)
			(layer "F.SilkS")
			(hide yes)
			(effects
				(font
					(size 1.27 1.27)
				)
			)
		)
		(property "Value" ""
			(at 0 0 0)
			(layer "F.Fab")
			(effects
				(font
					(size 1.27 1.27)
				)
			)
		)
		(duplicate_pad_numbers_are_jumpers no)
		(fp_line
			(start -0.7874 -0.4064)
			(end 0.7874 -0.4064)
			(stroke
				(width 0.1524)
				(type default)
			)
			(layer "F.SilkS")
		)
		(fp_line
			(start -0.7874 0.4064)
			(end -0.7874 -0.4064)
			(stroke
				(width 0.1524)
				(type default)
			)
			(layer "F.SilkS")
		)
		(fp_line
			(start 0.7874 -0.4064)
			(end 0.7874 0.4064)
			(stroke
				(width 0.1524)
				(type default)
			)
			(layer "F.SilkS")
		)
		(fp_line
			(start 0.7874 0.4064)
			(end -0.7874 0.4064)
			(stroke
				(width 0.1524)
				(type default)
			)
			(layer "F.SilkS")
		)
		(fp_line
			(start -0.67945 -0.305054)
			(end -0.12065 -0.305054)
			(stroke
				(width 0.1)
				(type default)
			)
			(layer "F.Fab")
		)
		(fp_line
			(start -0.67945 0.3048)
			(end -0.67945 -0.305054)
			(stroke
				(width 0.1)
				(type default)
			)
			(layer "F.Fab")
		)
		(fp_line
			(start -0.12065 -0.305054)
			(end -0.12065 -0.2794)
			(stroke
				(width 0.1)
				(type default)
			)
			(layer "F.Fab")
		)
		(fp_line
			(start -0.12065 -0.2794)
			(end 0.12065 -0.2794)
			(stroke
				(width 0.1)
				(type default)
			)
			(layer "F.Fab")
		)
		(fp_line
			(start -0.12065 0.2794)
			(end -0.12065 0.3048)
			(stroke
				(width 0.1)
				(type default)
			)
			(layer "F.Fab")
		)
		(fp_line
			(start -0.12065 0.3048)
			(end -0.67945 0.3048)
			(stroke
				(width 0.1)
				(type default)
			)
			(layer "F.Fab")
		)
		(fp_line
			(start 0.120396 0.2794)
			(end -0.12065 0.2794)
			(stroke
				(width 0.1)
				(type default)
			)
			(layer "F.Fab")
		)
		(fp_line
			(start 0.120396 0.3048)
			(end 0.120396 0.2794)
			(stroke
				(width 0.1)
				(type default)
			)
			(layer "F.Fab")
		)
		(fp_line
			(start 0.12065 -0.3048)
			(end 0.67945 -0.3048)
			(stroke
				(width 0.1)
				(type default)
			)
			(layer "F.Fab")
		)
		(fp_line
			(start 0.12065 -0.2794)
			(end 0.12065 -0.3048)
			(stroke
				(width 0.1)
				(type default)
			)
			(layer "F.Fab")
		)
		(fp_line
			(start 0.67945 -0.3048)
			(end 0.67945 0.3048)
			(stroke
				(width 0.1)
				(type default)
			)
			(layer "F.Fab")
		)
		(fp_line
			(start 0.67945 0.3048)
			(end 0.120396 0.3048)
			(stroke
				(width 0.1)
				(type default)
			)
			(layer "F.Fab")
		)
		(pad "1" smd circle
			(at -0.40005 0)
			(size 0 0)
			(layers "F.Cu" "F.Mask" "F.Paste")
			(net "PVDDIO_P0_LSET4")
		)
		(pad "2" smd circle
			(at 0.40005 0)
			(size 0 0)
			(layers "F.Cu" "F.Mask" "F.Paste")
			(net "GND")
		)
	)
)
